(kicad_pcb
	(version 20260206)
	(generator "pcbnew")
	(generator_version "10.0")
	(general
		(thickness 1.6)
		(legacy_teardrops no)
	)
	(paper "A4")
	(title_block
		(title "01162023_DA0F0TEBIF0_F0T_Expander_BD_F_brd_V02_OCP.brd")
		(comment 1 "Grand Teton / footprints 9319-9327 of 9728")
	)
	(layers
		(0 "F.Cu" signal "TOP")
		(4 "In1.Cu" signal "GND")
		(6 "In2.Cu" signal "VCC")
		(8 "In3.Cu" signal "VCC1")
		(10 "In4.Cu" signal "GND1")
		(12 "In5.Cu" signal "IN1")
		(14 "In6.Cu" signal "GND2")
		(16 "In7.Cu" signal "IN2")
		(18 "In8.Cu" signal "GND3")
		(20 "In9.Cu" signal "IN3")
		(22 "In10.Cu" signal "GND4")
		(24 "In11.Cu" signal "IN4")
		(26 "In12.Cu" signal "GND5")
		(28 "In13.Cu" signal "IN5")
		(30 "In14.Cu" signal "GND6")
		(32 "In15.Cu" signal "IN6")
		(34 "In16.Cu" signal "GND7")
		(2 "B.Cu" signal "BOTTOM")
		(9 "F.Adhes" user "F.Adhesive")
		(11 "B.Adhes" user "B.Adhesive")
		(13 "F.Paste" user "Package Geometry/Pastemask Top")
		(15 "B.Paste" user "Package Geometry/Pastemask Bottom")
		(5 "F.SilkS" user "Ref Des/Silkscreen Top")
		(7 "B.SilkS" user "Ref Des/Silkscreen Bottom")
		(1 "F.Mask" user "Board Geometry/Soldermask Top")
		(3 "B.Mask" user "Board Geometry/Soldermask Bottom")
		(17 "Dwgs.User" user "User.Drawings")
		(19 "Cmts.User" user "User.Comments")
		(21 "Eco1.User" user "User.Eco1")
		(23 "Eco2.User" user "User.Eco2")
		(25 "Edge.Cuts" user "Board Geometry/Outline")
		(27 "Margin" user)
		(31 "F.CrtYd" user "Package Geometry/Place Bound Top")
		(29 "B.CrtYd" user "Package Geometry/Place Bound Bottom")
		(35 "F.Fab" user "Ref Des/Assembly Top")
		(33 "B.Fab" user "Ref Des/Assembly Bottom")
	)
	(footprint ""
		(layer "B.Cu")
		(at 133.411214 -201.967846 90)
		(property "Reference" "C2592"
			(at 0 0 90)
			(layer "B.SilkS")
			(hide yes)
			(effects
				(font
					(size 1.27 1.27)
				)
				(justify mirror)
			)
		)
		(property "Value" ""
			(at 0 0 90)
			(layer "B.Fab")
			(effects
				(font
					(size 1.27 1.27)
				)
				(justify mirror)
			)
		)
		(duplicate_pad_numbers_are_jumpers no)
		(fp_line
			(start 0.7874 -0.4064)
			(end -0.7874 -0.4064)
			(stroke
				(width 0.1524)
				(type default)
			)
			(layer "B.SilkS")
		)
		(fp_line
			(start -0.7874 -0.4064)
			(end -0.7874 0.4064)
			(stroke
				(width 0.1524)
				(type default)
			)
			(layer "B.SilkS")
		)
		(fp_line
			(start 0.7874 0.4064)
			(end 0.7874 -0.4064)
			(stroke
				(width 0.1524)
				(type default)
			)
			(layer "B.SilkS")
		)
		(fp_line
			(start -0.7874 0.4064)
			(end 0.7874 0.4064)
			(stroke
				(width 0.1524)
				(type default)
			)
			(layer "B.SilkS")
		)
		(fp_line
			(start 0.67945 -0.305054)
			(end 0.12065 -0.305054)
			(stroke
				(width 0.1)
				(type default)
			)
			(layer "B.Fab")
		)
		(fp_line
			(start 0.12065 -0.305054)
			(end 0.12065 -0.2794)
			(stroke
				(width 0.1)
				(type default)
			)
			(layer "B.Fab")
		)
		(fp_line
			(start -0.12065 -0.3048)
			(end -0.67945 -0.3048)
			(stroke
				(width 0.1)
				(type default)
			)
			(layer "B.Fab")
		)
		(fp_line
			(start -0.67945 -0.3048)
			(end -0.67945 0.3048)
			(stroke
				(width 0.1)
				(type default)
			)
			(layer "B.Fab")
		)
		(fp_line
			(start 0.12065 -0.2794)
			(end -0.12065 -0.2794)
			(stroke
				(width 0.1)
				(type default)
			)
			(layer "B.Fab")
		)
		(fp_line
			(start -0.12065 -0.2794)
			(end -0.12065 -0.3048)
			(stroke
				(width 0.1)
				(type default)
			)
			(layer "B.Fab")
		)
		(fp_line
			(start 0.12065 0.2794)
			(end 0.12065 0.3048)
			(stroke
				(width 0.1)
				(type default)
			)
			(layer "B.Fab")
		)
		(fp_line
			(start -0.120396 0.2794)
			(end 0.12065 0.2794)
			(stroke
				(width 0.1)
				(type default)
			)
			(layer "B.Fab")
		)
		(fp_line
			(start 0.67945 0.3048)
			(end 0.67945 -0.305054)
			(stroke
				(width 0.1)
				(type default)
			)
			(layer "B.Fab")
		)
		(fp_line
			(start 0.12065 0.3048)
			(end 0.67945 0.3048)
			(stroke
				(width 0.1)
				(type default)
			)
			(layer "B.Fab")
		)
		(fp_line
			(start -0.120396 0.3048)
			(end -0.120396 0.2794)
			(stroke
				(width 0.1)
				(type default)
			)
			(layer "B.Fab")
		)
		(fp_line
			(start -0.67945 0.3048)
			(end -0.120396 0.3048)
			(stroke
				(width 0.1)
				(type default)
			)
			(layer "B.Fab")
		)
		(pad "1" smd circle
			(at 0.40005 0 270)
			(size 0 0)
			(layers "B.Cu" "B.Mask" "B.Paste")
			(net "P1V8_CLI_VCORE")
		)
		(pad "2" smd circle
			(at -0.40005 0 270)
			(size 0 0)
			(layers "B.Cu" "B.Mask" "B.Paste")
			(net "GND")
		)
	)
	(footprint ""
		(layer "B.Cu")
		(at 181.92496 -286.399732 90)
		(property "Reference" "C3148"
			(at 0 0 90)
			(layer "B.SilkS")
			(hide yes)
			(effects
				(font
					(size 1.27 1.27)
				)
				(justify mirror)
			)
		)
		(property "Value" ""
			(at 0 0 90)
			(layer "B.Fab")
			(effects
				(font
					(size 1.27 1.27)
				)
				(justify mirror)
			)
		)
		(duplicate_pad_numbers_are_jumpers no)
		(fp_line
			(start 0.299974 -0.150114)
			(end -0.299974 -0.150114)
			(stroke
				(width 0.1)
				(type default)
			)
			(layer "B.Fab")
		)
		(fp_line
			(start -0.299974 -0.150114)
			(end -0.299974 0.150114)
			(stroke
				(width 0.1)
				(type default)
			)
			(layer "B.Fab")
		)
		(fp_line
			(start 0.299974 0.150114)
			(end 0.299974 -0.150114)
			(stroke
				(width 0.1)
				(type default)
			)
			(layer "B.Fab")
		)
		(fp_line
			(start -0.299974 0.150114)
			(end 0.299974 0.150114)
			(stroke
				(width 0.1)
				(type default)
			)
			(layer "B.Fab")
		)
		(pad "1" smd rect
			(at 0.2667 0 270)
			(size 0.3048 0.381)
			(layers "B.Cu" "B.Mask" "B.Paste")
			(net "P1V25_SERDES_VDDPLL_PEX1")
		)
		(pad "2" smd rect
			(at -0.2667 0 270)
			(size 0.3048 0.381)
			(layers "B.Cu" "B.Mask" "B.Paste")
			(net "GND")
		)
	)
	(footprint ""
		(layer "B.Cu")
		(at 5.956554 -390.073642 90)
		(property "Reference" "C4472"
			(at 0 0 90)
			(layer "B.SilkS")
			(hide yes)
			(effects
				(font
					(size 1.27 1.27)
				)
				(justify mirror)
			)
		)
		(property "Value" ""
			(at 0 0 90)
			(layer "B.Fab")
			(effects
				(font
					(size 1.27 1.27)
				)
				(justify mirror)
			)
		)
		(duplicate_pad_numbers_are_jumpers no)
		(fp_line
			(start 0.7874 -0.4064)
			(end -0.7874 -0.4064)
			(stroke
				(width 0.1524)
				(type default)
			)
			(layer "B.SilkS")
		)
		(fp_line
			(start -0.7874 -0.4064)
			(end -0.7874 0.4064)
			(stroke
				(width 0.1524)
				(type default)
			)
			(layer "B.SilkS")
		)
		(fp_line
			(start 0.7874 0.4064)
			(end 0.7874 -0.4064)
			(stroke
				(width 0.1524)
				(type default)
			)
			(layer "B.SilkS")
		)
		(fp_line
			(start -0.7874 0.4064)
			(end 0.7874 0.4064)
			(stroke
				(width 0.1524)
				(type default)
			)
			(layer "B.SilkS")
		)
		(fp_line
			(start 0.67945 -0.305054)
			(end 0.12065 -0.305054)
			(stroke
				(width 0.1)
				(type default)
			)
			(layer "B.Fab")
		)
		(fp_line
			(start 0.12065 -0.305054)
			(end 0.12065 -0.2794)
			(stroke
				(width 0.1)
				(type default)
			)
			(layer "B.Fab")
		)
		(fp_line
			(start -0.12065 -0.3048)
			(end -0.67945 -0.3048)
			(stroke
				(width 0.1)
				(type default)
			)
			(layer "B.Fab")
		)
		(fp_line
			(start -0.67945 -0.3048)
			(end -0.67945 0.3048)
			(stroke
				(width 0.1)
				(type default)
			)
			(layer "B.Fab")
		)
		(fp_line
			(start 0.12065 -0.2794)
			(end -0.12065 -0.2794)
			(stroke
				(width 0.1)
				(type default)
			)
			(layer "B.Fab")
		)
		(fp_line
			(start -0.12065 -0.2794)
			(end -0.12065 -0.3048)
			(stroke
				(width 0.1)
				(type default)
			)
			(layer "B.Fab")
		)
		(fp_line
			(start 0.12065 0.2794)
			(end 0.12065 0.3048)
			(stroke
				(width 0.1)
				(type default)
			)
			(layer "B.Fab")
		)
		(fp_line
			(start -0.120396 0.2794)
			(end 0.12065 0.2794)
			(stroke
				(width 0.1)
				(type default)
			)
			(layer "B.Fab")
		)
		(fp_line
			(start 0.67945 0.3048)
			(end 0.67945 -0.305054)
			(stroke
				(width 0.1)
				(type default)
			)
			(layer "B.Fab")
		)
		(fp_line
			(start 0.12065 0.3048)
			(end 0.67945 0.3048)
			(stroke
				(width 0.1)
				(type default)
			)
			(layer "B.Fab")
		)
		(fp_line
			(start -0.120396 0.3048)
			(end -0.120396 0.2794)
			(stroke
				(width 0.1)
				(type default)
			)
			(layer "B.Fab")
		)
		(fp_line
			(start -0.67945 0.3048)
			(end -0.120396 0.3048)
			(stroke
				(width 0.1)
				(type default)
			)
			(layer "B.Fab")
		)
		(pad "1" smd circle
			(at 0.40005 0 270)
			(size 0 0)
			(layers "B.Cu" "B.Mask" "B.Paste")
			(net "P1V2_USB_8042")
		)
		(pad "2" smd circle
			(at -0.40005 0 270)
			(size 0 0)
			(layers "B.Cu" "B.Mask" "B.Paste")
			(net "GND")
		)
	)
	(footprint ""
		(layer "B.Cu")
		(at 5.617718 -264.586466)
		(property "Reference" "R6126"
			(at 0 0 0)
			(layer "B.SilkS")
			(hide yes)
			(effects
				(font
					(size 1.27 1.27)
				)
				(justify mirror)
			)
		)
		(property "Value" ""
			(at 0 0 0)
			(layer "B.Fab")
			(effects
				(font
					(size 1.27 1.27)
				)
				(justify mirror)
			)
		)
		(duplicate_pad_numbers_are_jumpers no)
		(fp_line
			(start -2.576322 -1.1303)
			(end -2.576322 1.1303)
			(stroke
				(width 0.1524)
				(type default)
			)
			(layer "B.SilkS")
		)
		(fp_line
			(start -2.576322 1.1303)
			(end 2.576322 1.1303)
			(stroke
				(width 0.1524)
				(type default)
			)
			(layer "B.SilkS")
		)
		(fp_line
			(start 2.576322 -1.1303)
			(end -2.576322 -1.1303)
			(stroke
				(width 0.1524)
				(type default)
			)
			(layer "B.SilkS")
		)
		(fp_line
			(start 2.576322 1.1303)
			(end 2.576322 -1.1303)
			(stroke
				(width 0.1524)
				(type default)
			)
			(layer "B.SilkS")
		)
		(fp_line
			(start -1.649984 -0.899922)
			(end 1.649984 -0.899922)
			(stroke
				(width 0.1)
				(type default)
			)
			(layer "B.Fab")
		)
		(fp_line
			(start -1.649984 0.899922)
			(end -1.649984 -0.899922)
			(stroke
				(width 0.1)
				(type default)
			)
			(layer "B.Fab")
		)
		(fp_line
			(start 1.649984 -0.899922)
			(end 1.649984 0.899922)
			(stroke
				(width 0.1)
				(type default)
			)
			(layer "B.Fab")
		)
		(fp_line
			(start 1.649984 0.899922)
			(end -1.649984 0.899922)
			(stroke
				(width 0.1)
				(type default)
			)
			(layer "B.Fab")
		)
		(pad "1A" smd rect
			(at 1.700022 0 180)
			(size 1.4986 2.0066)
			(layers "B.Cu" "B.Mask" "B.Paste")
			(net "P1V25_PEX0")
		)
		(pad "1B" smd rect
			(at 1.077722 0 180)
			(size 0.254 0.508)
			(layers "B.Cu" "B.Mask" "B.Paste")
			(net "P1V25_PEX0")
		)
		(pad "2A" smd rect
			(at -1.700022 0 180)
			(size 1.4986 2.0066)
			(layers "B.Cu" "B.Mask" "B.Paste")
			(net "P1V25_SERDES_VDDPLL_PEX0")
		)
		(pad "2B" smd rect
			(at -1.077722 0 180)
			(size 0.254 0.508)
			(layers "B.Cu" "B.Mask" "B.Paste")
			(net "P1V25_SERDES_VDDPLL_PEX0")
		)
	)
	(footprint ""
		(layer "B.Cu")
		(at 403.674834 -297.79976 90)
		(property "Reference" "C1885"
			(at 0 0 90)
			(layer "B.SilkS")
			(hide yes)
			(effects
				(font
					(size 1.27 1.27)
				)
				(justify mirror)
			)
		)
		(property "Value" ""
			(at 0 0 90)
			(layer "B.Fab")
			(effects
				(font
					(size 1.27 1.27)
				)
				(justify mirror)
			)
		)
		(duplicate_pad_numbers_are_jumpers no)
		(fp_line
			(start 0.299974 -0.150114)
			(end -0.299974 -0.150114)
			(stroke
				(width 0.1)
				(type default)
			)
			(layer "B.Fab")
		)
		(fp_line
			(start -0.299974 -0.150114)
			(end -0.299974 0.150114)
			(stroke
				(width 0.1)
				(type default)
			)
			(layer "B.Fab")
		)
		(fp_line
			(start 0.299974 0.150114)
			(end 0.299974 -0.150114)
			(stroke
				(width 0.1)
				(type default)
			)
			(layer "B.Fab")
		)
		(fp_line
			(start -0.299974 0.150114)
			(end 0.299974 0.150114)
			(stroke
				(width 0.1)
				(type default)
			)
			(layer "B.Fab")
		)
		(pad "1" smd rect
			(at 0.2667 0 270)
			(size 0.3048 0.381)
			(layers "B.Cu" "B.Mask" "B.Paste")
			(net "P0V8_PEX3")
		)
		(pad "2" smd rect
			(at -0.2667 0 270)
			(size 0.3048 0.381)
			(layers "B.Cu" "B.Mask" "B.Paste")
			(net "GND")
		)
	)
	(footprint ""
		(layer "B.Cu")
		(at 276.93366 -389.498078 180)
		(property "Reference" "PR7158"
			(at 0 0 0)
			(layer "B.SilkS")
			(hide yes)
			(effects
				(font
					(size 1.27 1.27)
				)
				(justify mirror)
			)
		)
		(property "Value" ""
			(at 0 0 0)
			(layer "B.Fab")
			(effects
				(font
					(size 1.27 1.27)
				)
				(justify mirror)
			)
		)
		(duplicate_pad_numbers_are_jumpers no)
		(fp_line
			(start 0.7874 0.4064)
			(end 0.7874 -0.4064)
			(stroke
				(width 0.1524)
				(type default)
			)
			(layer "B.SilkS")
		)
		(fp_line
			(start 0.7874 -0.4064)
			(end -0.7874 -0.4064)
			(stroke
				(width 0.1524)
				(type default)
			)
			(layer "B.SilkS")
		)
		(fp_line
			(start -0.7874 0.4064)
			(end 0.7874 0.4064)
			(stroke
				(width 0.1524)
				(type default)
			)
			(layer "B.SilkS")
		)
		(fp_line
			(start -0.7874 -0.4064)
			(end -0.7874 0.4064)
			(stroke
				(width 0.1524)
				(type default)
			)
			(layer "B.SilkS")
		)
		(fp_line
			(start 0.67945 0.3048)
			(end 0.67945 -0.305054)
			(stroke
				(width 0.1)
				(type default)
			)
			(layer "B.Fab")
		)
		(fp_line
			(start 0.67945 -0.305054)
			(end 0.12065 -0.305054)
			(stroke
				(width 0.1)
				(type default)
			)
			(layer "B.Fab")
		)
		(fp_line
			(start 0.12065 0.3048)
			(end 0.67945 0.3048)
			(stroke
				(width 0.1)
				(type default)
			)
			(layer "B.Fab")
		)
		(fp_line
			(start 0.12065 0.2794)
			(end 0.12065 0.3048)
			(stroke
				(width 0.1)
				(type default)
			)
			(layer "B.Fab")
		)
		(fp_line
			(start 0.12065 -0.2794)
			(end -0.12065 -0.2794)
			(stroke
				(width 0.1)
				(type default)
			)
			(layer "B.Fab")
		)
		(fp_line
			(start 0.12065 -0.305054)
			(end 0.12065 -0.2794)
			(stroke
				(width 0.1)
				(type default)
			)
			(layer "B.Fab")
		)
		(fp_line
			(start -0.120396 0.3048)
			(end -0.120396 0.2794)
			(stroke
				(width 0.1)
				(type default)
			)
			(layer "B.Fab")
		)
		(fp_line
			(start -0.120396 0.2794)
			(end 0.12065 0.2794)
			(stroke
				(width 0.1)
				(type default)
			)
			(layer "B.Fab")
		)
		(fp_line
			(start -0.12065 -0.2794)
			(end -0.12065 -0.3048)
			(stroke
				(width 0.1)
				(type default)
			)
			(layer "B.Fab")
		)
		(fp_line
			(start -0.12065 -0.3048)
			(end -0.67945 -0.3048)
			(stroke
				(width 0.1)
				(type default)
			)
			(layer "B.Fab")
		)
		(fp_line
			(start -0.67945 0.3048)
			(end -0.120396 0.3048)
			(stroke
				(width 0.1)
				(type default)
			)
			(layer "B.Fab")
		)
		(fp_line
			(start -0.67945 -0.3048)
			(end -0.67945 0.3048)
			(stroke
				(width 0.1)
				(type default)
			)
			(layer "B.Fab")
		)
		(pad "1" smd circle
			(at 0.40005 0)
			(size 0 0)
			(layers "B.Cu" "B.Mask" "B.Paste")
			(net "HSC_ALERT1_R_N")
		)
		(pad "2" smd circle
			(at -0.40005 0)
			(size 0 0)
			(layers "B.Cu" "B.Mask" "B.Paste")
			(net "P3V3_AUX")
		)
	)
	(footprint ""
		(layer "B.Cu")
		(at 71.755 -97.663 180)
		(property "Reference" "R73"
			(at 0 0 0)
			(layer "B.SilkS")
			(hide yes)
			(effects
				(font
					(size 1.27 1.27)
				)
				(justify mirror)
			)
		)
		(property "Value" ""
			(at 0 0 0)
			(layer "B.Fab")
			(effects
				(font
					(size 1.27 1.27)
				)
				(justify mirror)
			)
		)
		(duplicate_pad_numbers_are_jumpers no)
		(fp_line
			(start 0.7874 0.4064)
			(end 0.7874 -0.4064)
			(stroke
				(width 0.1524)
				(type default)
			)
			(layer "B.SilkS")
		)
		(fp_line
			(start 0.7874 -0.4064)
			(end -0.7874 -0.4064)
			(stroke
				(width 0.1524)
				(type default)
			)
			(layer "B.SilkS")
		)
		(fp_line
			(start -0.7874 0.4064)
			(end 0.7874 0.4064)
			(stroke
				(width 0.1524)
				(type default)
			)
			(layer "B.SilkS")
		)
		(fp_line
			(start -0.7874 -0.4064)
			(end -0.7874 0.4064)
			(stroke
				(width 0.1524)
				(type default)
			)
			(layer "B.SilkS")
		)
		(fp_line
			(start 0.67945 0.3048)
			(end 0.67945 -0.305054)
			(stroke
				(width 0.1)
				(type default)
			)
			(layer "B.Fab")
		)
		(fp_line
			(start 0.67945 -0.305054)
			(end 0.12065 -0.305054)
			(stroke
				(width 0.1)
				(type default)
			)
			(layer "B.Fab")
		)
		(fp_line
			(start 0.12065 0.3048)
			(end 0.67945 0.3048)
			(stroke
				(width 0.1)
				(type default)
			)
			(layer "B.Fab")
		)
		(fp_line
			(start 0.12065 0.2794)
			(end 0.12065 0.3048)
			(stroke
				(width 0.1)
				(type default)
			)
			(layer "B.Fab")
		)
		(fp_line
			(start 0.12065 -0.2794)
			(end -0.12065 -0.2794)
			(stroke
				(width 0.1)
				(type default)
			)
			(layer "B.Fab")
		)
		(fp_line
			(start 0.12065 -0.305054)
			(end 0.12065 -0.2794)
			(stroke
				(width 0.1)
				(type default)
			)
			(layer "B.Fab")
		)
		(fp_line
			(start -0.120396 0.3048)
			(end -0.120396 0.2794)
			(stroke
				(width 0.1)
				(type default)
			)
			(layer "B.Fab")
		)
		(fp_line
			(start -0.120396 0.2794)
			(end 0.12065 0.2794)
			(stroke
				(width 0.1)
				(type default)
			)
			(layer "B.Fab")
		)
		(fp_line
			(start -0.12065 -0.2794)
			(end -0.12065 -0.3048)
			(stroke
				(width 0.1)
				(type default)
			)
			(layer "B.Fab")
		)
		(fp_line
			(start -0.12065 -0.3048)
			(end -0.67945 -0.3048)
			(stroke
				(width 0.1)
				(type default)
			)
			(layer "B.Fab")
		)
		(fp_line
			(start -0.67945 0.3048)
			(end -0.120396 0.3048)
			(stroke
				(width 0.1)
				(type default)
			)
			(layer "B.Fab")
		)
		(fp_line
			(start -0.67945 -0.3048)
			(end -0.67945 0.3048)
			(stroke
				(width 0.1)
				(type default)
			)
			(layer "B.Fab")
		)
		(pad "1" smd circle
			(at 0.40005 0)
			(size 0 0)
			(layers "B.Cu" "B.Mask" "B.Paste")
			(net "PWRGD_NIC1_PWR_GOOD")
		)
		(pad "2" smd circle
			(at -0.40005 0)
			(size 0 0)
			(layers "B.Cu" "B.Mask" "B.Paste")
			(net "GND")
		)
	)
	(footprint ""
		(layer "B.Cu")
		(at 62.024768 -286.399732 90)
		(property "Reference" "C2961"
			(at 0 0 90)
			(layer "B.SilkS")
			(hide yes)
			(effects
				(font
					(size 1.27 1.27)
				)
				(justify mirror)
			)
		)
		(property "Value" ""
			(at 0 0 90)
			(layer "B.Fab")
			(effects
				(font
					(size 1.27 1.27)
				)
				(justify mirror)
			)
		)
		(duplicate_pad_numbers_are_jumpers no)
		(fp_line
			(start 0.299974 -0.150114)
			(end -0.299974 -0.150114)
			(stroke
				(width 0.1)
				(type default)
			)
			(layer "B.Fab")
		)
		(fp_line
			(start -0.299974 -0.150114)
			(end -0.299974 0.150114)
			(stroke
				(width 0.1)
				(type default)
			)
			(layer "B.Fab")
		)
		(fp_line
			(start 0.299974 0.150114)
			(end 0.299974 -0.150114)
			(stroke
				(width 0.1)
				(type default)
			)
			(layer "B.Fab")
		)
		(fp_line
			(start -0.299974 0.150114)
			(end 0.299974 0.150114)
			(stroke
				(width 0.1)
				(type default)
			)
			(layer "B.Fab")
		)
		(pad "1" smd rect
			(at 0.2667 0 270)
			(size 0.3048 0.381)
			(layers "B.Cu" "B.Mask" "B.Paste")
			(net "P1V25_SERDES_VDDPLL_PEX0")
		)
		(pad "2" smd rect
			(at -0.2667 0 270)
			(size 0.3048 0.381)
			(layers "B.Cu" "B.Mask" "B.Paste")
			(net "GND")
		)
	)
	(footprint ""
		(layer "B.Cu")
		(at 282.770072 -305.399948 -90)
		(property "Reference" "C3318"
			(at 0 0 90)
			(layer "B.SilkS")
			(hide yes)
			(effects
				(font
					(size 1.27 1.27)
				)
				(justify mirror)
			)
		)
		(property "Value" ""
			(at 0 0 90)
			(layer "B.Fab")
			(effects
				(font
					(size 1.27 1.27)
				)
				(justify mirror)
			)
		)
		(duplicate_pad_numbers_are_jumpers no)
		(fp_line
			(start -0.299974 0.150114)
			(end 0.299974 0.150114)
			(stroke
				(width 0.1)
				(type default)
			)
			(layer "B.Fab")
		)
		(fp_line
			(start 0.299974 0.150114)
			(end 0.299974 -0.150114)
			(stroke
				(width 0.1)
				(type default)
			)
			(layer "B.Fab")
		)
		(fp_line
			(start -0.299974 -0.150114)
			(end -0.299974 0.150114)
			(stroke
				(width 0.1)
				(type default)
			)
			(layer "B.Fab")
		)
		(fp_line
			(start 0.299974 -0.150114)
			(end -0.299974 -0.150114)
			(stroke
				(width 0.1)
				(type default)
			)
			(layer "B.Fab")
		)
		(pad "1" smd rect
			(at 0.2667 0 90)
			(size 0.3048 0.381)
			(layers "B.Cu" "B.Mask" "B.Paste")
			(net "P1V25_SERDES_VDDPLL_PEX2")
		)
		(pad "2" smd rect
			(at -0.2667 0 90)
			(size 0.3048 0.381)
			(layers "B.Cu" "B.Mask" "B.Paste")
			(net "GND")
		)
	)
)
